(kicad_pcb
	(version 20260206)
	(generator "pcbnew")
	(generator_version "10.0")
	(general
		(thickness 1.6)
		(legacy_teardrops no)
	)
	(paper "A4")
	(title_block
		(title "04192023_DAF0TMB3IC0_F0TG_MB_C_brd_V02_OCP.brd")
		(comment 1 "Grand Teton / footprints 7032-7039 of 8354")
	)
	(layers
		(0 "F.Cu" signal "TOP")
		(4 "In1.Cu" signal "GND")
		(6 "In2.Cu" signal "IN1")
		(8 "In3.Cu" signal "GND1")
		(10 "In4.Cu" signal "IN2")
		(12 "In5.Cu" signal "GND2")
		(14 "In6.Cu" signal "IN3")
		(16 "In7.Cu" signal "GND3")
		(18 "In8.Cu" signal "VCC")
		(20 "In9.Cu" signal "VCC1")
		(22 "In10.Cu" signal "GND4")
		(24 "In11.Cu" signal "IN4")
		(26 "In12.Cu" signal "GND5")
		(28 "In13.Cu" signal "IN5")
		(30 "In14.Cu" signal "GND6")
		(32 "In15.Cu" signal "IN6")
		(34 "In16.Cu" signal "GND7")
		(2 "B.Cu" signal "BOTTOM")
		(9 "F.Adhes" user "F.Adhesive")
		(11 "B.Adhes" user "B.Adhesive")
		(13 "F.Paste" user "Package Geometry/Pastemask Top")
		(15 "B.Paste" user "Package Geometry/Pastemask Bottom")
		(5 "F.SilkS" user "Ref Des/Silkscreen Top")
		(7 "B.SilkS" user "Ref Des/Silkscreen Bottom")
		(1 "F.Mask" user "Board Geometry/Soldermask Top")
		(3 "B.Mask" user "Board Geometry/Soldermask Bottom")
		(17 "Dwgs.User" user "User.Drawings")
		(19 "Cmts.User" user "User.Comments")
		(21 "Eco1.User" user "User.Eco1")
		(23 "Eco2.User" user "User.Eco2")
		(25 "Edge.Cuts" user "Board Geometry/Outline")
		(27 "Margin" user)
		(31 "F.CrtYd" user "Package Geometry/Place Bound Top")
		(29 "B.CrtYd" user "Package Geometry/Place Bound Bottom")
		(35 "F.Fab" user "Ref Des/Assembly Top")
		(33 "B.Fab" user "Ref Des/Assembly Bottom")
	)
	(footprint ""
		(layer "B.Cu")
		(at 165.183566 -194.885564 180)
		(property "Reference" "R37"
			(at 0 0 0)
			(layer "B.SilkS")
			(hide yes)
			(effects
				(font
					(size 1.27 1.27)
				)
				(justify mirror)
			)
		)
		(property "Value" ""
			(at 0 0 0)
			(layer "B.Fab")
			(effects
				(font
					(size 1.27 1.27)
				)
				(justify mirror)
			)
		)
		(duplicate_pad_numbers_are_jumpers no)
		(fp_line
			(start 0.7874 0.4064)
			(end 0.7874 -0.4064)
			(stroke
				(width 0.1524)
				(type default)
			)
			(layer "B.SilkS")
		)
		(fp_line
			(start 0.7874 -0.4064)
			(end -0.7874 -0.4064)
			(stroke
				(width 0.1524)
				(type default)
			)
			(layer "B.SilkS")
		)
		(fp_line
			(start -0.7874 0.4064)
			(end 0.7874 0.4064)
			(stroke
				(width 0.1524)
				(type default)
			)
			(layer "B.SilkS")
		)
		(fp_line
			(start -0.7874 -0.4064)
			(end -0.7874 0.4064)
			(stroke
				(width 0.1524)
				(type default)
			)
			(layer "B.SilkS")
		)
		(fp_line
			(start 0.67945 0.3048)
			(end 0.67945 -0.305054)
			(stroke
				(width 0.1)
				(type default)
			)
			(layer "B.Fab")
		)
		(fp_line
			(start 0.67945 -0.305054)
			(end 0.12065 -0.305054)
			(stroke
				(width 0.1)
				(type default)
			)
			(layer "B.Fab")
		)
		(fp_line
			(start 0.12065 0.3048)
			(end 0.67945 0.3048)
			(stroke
				(width 0.1)
				(type default)
			)
			(layer "B.Fab")
		)
		(fp_line
			(start 0.12065 0.2794)
			(end 0.12065 0.3048)
			(stroke
				(width 0.1)
				(type default)
			)
			(layer "B.Fab")
		)
		(fp_line
			(start 0.12065 -0.2794)
			(end -0.12065 -0.2794)
			(stroke
				(width 0.1)
				(type default)
			)
			(layer "B.Fab")
		)
		(fp_line
			(start 0.12065 -0.305054)
			(end 0.12065 -0.2794)
			(stroke
				(width 0.1)
				(type default)
			)
			(layer "B.Fab")
		)
		(fp_line
			(start -0.120396 0.3048)
			(end -0.120396 0.2794)
			(stroke
				(width 0.1)
				(type default)
			)
			(layer "B.Fab")
		)
		(fp_line
			(start -0.120396 0.2794)
			(end 0.12065 0.2794)
			(stroke
				(width 0.1)
				(type default)
			)
			(layer "B.Fab")
		)
		(fp_line
			(start -0.12065 -0.2794)
			(end -0.12065 -0.3048)
			(stroke
				(width 0.1)
				(type default)
			)
			(layer "B.Fab")
		)
		(fp_line
			(start -0.12065 -0.3048)
			(end -0.67945 -0.3048)
			(stroke
				(width 0.1)
				(type default)
			)
			(layer "B.Fab")
		)
		(fp_line
			(start -0.67945 0.3048)
			(end -0.120396 0.3048)
			(stroke
				(width 0.1)
				(type default)
			)
			(layer "B.Fab")
		)
		(fp_line
			(start -0.67945 -0.3048)
			(end -0.67945 0.3048)
			(stroke
				(width 0.1)
				(type default)
			)
			(layer "B.Fab")
		)
		(pad "1" smd circle
			(at 0.40005 0)
			(size 0 0)
			(layers "B.Cu" "B.Mask" "B.Paste")
			(net "PD_CHG_CPU1_DIMM0_SAA")
		)
		(pad "2" smd circle
			(at -0.40005 0)
			(size 0 0)
			(layers "B.Cu" "B.Mask" "B.Paste")
			(net "GND")
		)
	)
	(footprint ""
		(layer "B.Cu")
		(at 199.39 -144.272 90)
		(property "Reference" "C8012"
			(at 0 0 90)
			(layer "B.SilkS")
			(hide yes)
			(effects
				(font
					(size 1.27 1.27)
				)
				(justify mirror)
			)
		)
		(property "Value" ""
			(at 0 0 90)
			(layer "B.Fab")
			(effects
				(font
					(size 1.27 1.27)
				)
				(justify mirror)
			)
		)
		(duplicate_pad_numbers_are_jumpers no)
		(fp_line
			(start 0.7874 -0.4064)
			(end -0.7874 -0.4064)
			(stroke
				(width 0.1524)
				(type default)
			)
			(layer "B.SilkS")
		)
		(fp_line
			(start -0.7874 -0.4064)
			(end -0.7874 0.4064)
			(stroke
				(width 0.1524)
				(type default)
			)
			(layer "B.SilkS")
		)
		(fp_line
			(start 0.7874 0.4064)
			(end 0.7874 -0.4064)
			(stroke
				(width 0.1524)
				(type default)
			)
			(layer "B.SilkS")
		)
		(fp_line
			(start -0.7874 0.4064)
			(end 0.7874 0.4064)
			(stroke
				(width 0.1524)
				(type default)
			)
			(layer "B.SilkS")
		)
		(fp_line
			(start 0.67945 -0.305054)
			(end 0.12065 -0.305054)
			(stroke
				(width 0.1)
				(type default)
			)
			(layer "B.Fab")
		)
		(fp_line
			(start 0.12065 -0.305054)
			(end 0.12065 -0.2794)
			(stroke
				(width 0.1)
				(type default)
			)
			(layer "B.Fab")
		)
		(fp_line
			(start -0.12065 -0.3048)
			(end -0.67945 -0.3048)
			(stroke
				(width 0.1)
				(type default)
			)
			(layer "B.Fab")
		)
		(fp_line
			(start -0.67945 -0.3048)
			(end -0.67945 0.3048)
			(stroke
				(width 0.1)
				(type default)
			)
			(layer "B.Fab")
		)
		(fp_line
			(start 0.12065 -0.2794)
			(end -0.12065 -0.2794)
			(stroke
				(width 0.1)
				(type default)
			)
			(layer "B.Fab")
		)
		(fp_line
			(start -0.12065 -0.2794)
			(end -0.12065 -0.3048)
			(stroke
				(width 0.1)
				(type default)
			)
			(layer "B.Fab")
		)
		(fp_line
			(start 0.12065 0.2794)
			(end 0.12065 0.3048)
			(stroke
				(width 0.1)
				(type default)
			)
			(layer "B.Fab")
		)
		(fp_line
			(start -0.120396 0.2794)
			(end 0.12065 0.2794)
			(stroke
				(width 0.1)
				(type default)
			)
			(layer "B.Fab")
		)
		(fp_line
			(start 0.67945 0.3048)
			(end 0.67945 -0.305054)
			(stroke
				(width 0.1)
				(type default)
			)
			(layer "B.Fab")
		)
		(fp_line
			(start 0.12065 0.3048)
			(end 0.67945 0.3048)
			(stroke
				(width 0.1)
				(type default)
			)
			(layer "B.Fab")
		)
		(fp_line
			(start -0.120396 0.3048)
			(end -0.120396 0.2794)
			(stroke
				(width 0.1)
				(type default)
			)
			(layer "B.Fab")
		)
		(fp_line
			(start -0.67945 0.3048)
			(end -0.120396 0.3048)
			(stroke
				(width 0.1)
				(type default)
			)
			(layer "B.Fab")
		)
		(pad "1" smd circle
			(at 0.40005 0 270)
			(size 0 0)
			(layers "B.Cu" "B.Mask" "B.Paste")
			(net "FM_AC_PWR_BTN_R_N")
		)
		(pad "2" smd circle
			(at -0.40005 0 270)
			(size 0 0)
			(layers "B.Cu" "B.Mask" "B.Paste")
			(net "GND")
		)
	)
	(footprint ""
		(layer "B.Cu")
		(at 142.047214 -390.587484)
		(property "Reference" "C405"
			(at 0 0 0)
			(layer "B.SilkS")
			(hide yes)
			(effects
				(font
					(size 1.27 1.27)
				)
				(justify mirror)
			)
		)
		(property "Value" ""
			(at 0 0 0)
			(layer "B.Fab")
			(effects
				(font
					(size 1.27 1.27)
				)
				(justify mirror)
			)
		)
		(duplicate_pad_numbers_are_jumpers no)
		(fp_line
			(start -1.524 -0.762)
			(end -1.524 0.762)
			(stroke
				(width 0.1524)
				(type default)
			)
			(layer "B.SilkS")
		)
		(fp_line
			(start -1.524 0.762)
			(end 1.524 0.762)
			(stroke
				(width 0.1524)
				(type default)
			)
			(layer "B.SilkS")
		)
		(fp_line
			(start 1.524 -0.762)
			(end -1.524 -0.762)
			(stroke
				(width 0.1524)
				(type default)
			)
			(layer "B.SilkS")
		)
		(fp_line
			(start 1.524 0.762)
			(end 1.524 -0.762)
			(stroke
				(width 0.1524)
				(type default)
			)
			(layer "B.SilkS")
		)
		(fp_line
			(start -1.1049 -0.724916)
			(end 1.1049 -0.724916)
			(stroke
				(width 0.1)
				(type default)
			)
			(layer "B.Fab")
		)
		(fp_line
			(start -1.1049 0.724916)
			(end -1.1049 -0.724916)
			(stroke
				(width 0.1)
				(type default)
			)
			(layer "B.Fab")
		)
		(fp_line
			(start 1.1049 -0.724916)
			(end 1.1049 0.724916)
			(stroke
				(width 0.1)
				(type default)
			)
			(layer "B.Fab")
		)
		(fp_line
			(start 1.1049 0.724916)
			(end -1.1049 0.724916)
			(stroke
				(width 0.1)
				(type default)
			)
			(layer "B.Fab")
		)
		(pad "1" smd rect
			(at 0.889 0)
			(size 1.016 1.27)
			(layers "B.Cu" "B.Mask" "B.Paste")
			(net "P0V9_CPU1_RT2_2A")
		)
		(pad "2" smd rect
			(at -0.889 0)
			(size 1.016 1.27)
			(layers "B.Cu" "B.Mask" "B.Paste")
			(net "GND")
		)
	)
	(footprint ""
		(layer "B.Cu")
		(at 85.906356 -386.766562 90)
		(property "Reference" "C292"
			(at 0 0 90)
			(layer "B.SilkS")
			(hide yes)
			(effects
				(font
					(size 1.27 1.27)
				)
				(justify mirror)
			)
		)
		(property "Value" ""
			(at 0 0 90)
			(layer "B.Fab")
			(effects
				(font
					(size 1.27 1.27)
				)
				(justify mirror)
			)
		)
		(duplicate_pad_numbers_are_jumpers no)
		(fp_line
			(start 0.299974 -0.150114)
			(end -0.299974 -0.150114)
			(stroke
				(width 0.1)
				(type default)
			)
			(layer "B.Fab")
		)
		(fp_line
			(start -0.299974 -0.150114)
			(end -0.299974 0.150114)
			(stroke
				(width 0.1)
				(type default)
			)
			(layer "B.Fab")
		)
		(fp_line
			(start 0.299974 0.150114)
			(end 0.299974 -0.150114)
			(stroke
				(width 0.1)
				(type default)
			)
			(layer "B.Fab")
		)
		(fp_line
			(start -0.299974 0.150114)
			(end 0.299974 0.150114)
			(stroke
				(width 0.1)
				(type default)
			)
			(layer "B.Fab")
		)
		(pad "1" smd rect
			(at 0.2667 0 270)
			(size 0.3048 0.381)
			(layers "B.Cu" "B.Mask" "B.Paste")
			(net "P0V9_CPU1_RT_2D")
		)
		(pad "2" smd rect
			(at -0.2667 0 270)
			(size 0.3048 0.381)
			(layers "B.Cu" "B.Mask" "B.Paste")
			(net "GND")
		)
	)
	(footprint ""
		(layer "B.Cu")
		(at 332.869286 -416.899344 90)
		(property "Reference" "C6552"
			(at 0 0 90)
			(layer "B.SilkS")
			(hide yes)
			(effects
				(font
					(size 1.27 1.27)
				)
				(justify mirror)
			)
		)
		(property "Value" ""
			(at 0 0 90)
			(layer "B.Fab")
			(effects
				(font
					(size 1.27 1.27)
				)
				(justify mirror)
			)
		)
		(duplicate_pad_numbers_are_jumpers no)
		(fp_line
			(start 0.299974 -0.150114)
			(end -0.299974 -0.150114)
			(stroke
				(width 0.1)
				(type default)
			)
			(layer "B.Fab")
		)
		(fp_line
			(start -0.299974 -0.150114)
			(end -0.299974 0.150114)
			(stroke
				(width 0.1)
				(type default)
			)
			(layer "B.Fab")
		)
		(fp_line
			(start 0.299974 0.150114)
			(end 0.299974 -0.150114)
			(stroke
				(width 0.1)
				(type default)
			)
			(layer "B.Fab")
		)
		(fp_line
			(start -0.299974 0.150114)
			(end 0.299974 0.150114)
			(stroke
				(width 0.1)
				(type default)
			)
			(layer "B.Fab")
		)
		(pad "1" smd rect
			(at 0.2667 0 270)
			(size 0.3048 0.381)
			(layers "B.Cu" "B.Mask" "B.Paste")
			(net "P5E_CPU0_P1_TX_BUF_C_DN<9>")
		)
		(pad "2" smd rect
			(at -0.2667 0 270)
			(size 0.3048 0.381)
			(layers "B.Cu" "B.Mask" "B.Paste")
			(net "P5E_CPU0_P1_TX_BUF_DN<9>")
		)
	)
	(footprint ""
		(layer "B.Cu")
		(at 230.6828 -335.026 180)
		(property "Reference" "R6760"
			(at 0 0 0)
			(layer "B.SilkS")
			(hide yes)
			(effects
				(font
					(size 1.27 1.27)
				)
				(justify mirror)
			)
		)
		(property "Value" ""
			(at 0 0 0)
			(layer "B.Fab")
			(effects
				(font
					(size 1.27 1.27)
				)
				(justify mirror)
			)
		)
		(duplicate_pad_numbers_are_jumpers no)
		(fp_line
			(start 0.32512 0.175006)
			(end 0.32512 -0.175006)
			(stroke
				(width 0.1)
				(type default)
			)
			(layer "B.Fab")
		)
		(fp_line
			(start 0.32512 -0.175006)
			(end -0.32512 -0.175006)
			(stroke
				(width 0.1)
				(type default)
			)
			(layer "B.Fab")
		)
		(fp_line
			(start -0.32512 0.175006)
			(end 0.32512 0.175006)
			(stroke
				(width 0.1)
				(type default)
			)
			(layer "B.Fab")
		)
		(fp_line
			(start -0.32512 -0.175006)
			(end -0.32512 0.175006)
			(stroke
				(width 0.1)
				(type default)
			)
			(layer "B.Fab")
		)
		(pad "1" smd rect
			(at 0.2667 0)
			(size 0.3048 0.381)
			(layers "B.Cu" "B.Mask" "B.Paste")
			(net "SMB_RT_CPU0_P2_SDA")
		)
		(pad "2" smd rect
			(at -0.2667 0 180)
			(size 0.3048 0.381)
			(layers "B.Cu" "B.Mask" "B.Paste")
			(net "SMB_RT_CPU0_P2_R_SDA")
		)
	)
	(footprint ""
		(layer "B.Cu")
		(at 443.013592 -389.14832 -90)
		(property "Reference" "PC6587_2"
			(at 0 0 90)
			(layer "B.SilkS")
			(hide yes)
			(effects
				(font
					(size 1.27 1.27)
				)
				(justify mirror)
			)
		)
		(property "Value" ""
			(at 0 0 90)
			(layer "B.Fab")
			(effects
				(font
					(size 1.27 1.27)
				)
				(justify mirror)
			)
		)
		(duplicate_pad_numbers_are_jumpers no)
		(fp_line
			(start -1.524 0.762)
			(end 1.524 0.762)
			(stroke
				(width 0.1524)
				(type default)
			)
			(layer "B.SilkS")
		)
		(fp_line
			(start 1.524 0.762)
			(end 1.524 -0.762)
			(stroke
				(width 0.1524)
				(type default)
			)
			(layer "B.SilkS")
		)
		(fp_line
			(start -1.524 -0.762)
			(end -1.524 0.762)
			(stroke
				(width 0.1524)
				(type default)
			)
			(layer "B.SilkS")
		)
		(fp_line
			(start 1.524 -0.762)
			(end -1.524 -0.762)
			(stroke
				(width 0.1524)
				(type default)
			)
			(layer "B.SilkS")
		)
		(fp_line
			(start -1.1049 0.724916)
			(end -1.1049 -0.724916)
			(stroke
				(width 0.1)
				(type default)
			)
			(layer "B.Fab")
		)
		(fp_line
			(start 1.1049 0.724916)
			(end -1.1049 0.724916)
			(stroke
				(width 0.1)
				(type default)
			)
			(layer "B.Fab")
		)
		(fp_line
			(start -1.1049 -0.724916)
			(end 1.1049 -0.724916)
			(stroke
				(width 0.1)
				(type default)
			)
			(layer "B.Fab")
		)
		(fp_line
			(start 1.1049 -0.724916)
			(end 1.1049 0.724916)
			(stroke
				(width 0.1)
				(type default)
			)
			(layer "B.Fab")
		)
		(pad "1" smd rect
			(at 0.889 0 270)
			(size 1.016 1.27)
			(layers "B.Cu" "B.Mask" "B.Paste")
			(net "P0V9_CPU0_RT_2D")
		)
		(pad "2" smd rect
			(at -0.889 0 270)
			(size 1.016 1.27)
			(layers "B.Cu" "B.Mask" "B.Paste")
			(net "GND")
		)
	)
	(footprint ""
		(layer "B.Cu")
		(at 448.579748 -10.567162 -90)
		(property "Reference" "R31"
			(at 0 0 90)
			(layer "B.SilkS")
			(hide yes)
			(effects
				(font
					(size 1.27 1.27)
				)
				(justify mirror)
			)
		)
		(property "Value" ""
			(at 0 0 90)
			(layer "B.Fab")
			(effects
				(font
					(size 1.27 1.27)
				)
				(justify mirror)
			)
		)
		(duplicate_pad_numbers_are_jumpers no)
		(fp_line
			(start -0.7874 0.4064)
			(end 0.7874 0.4064)
			(stroke
				(width 0.1524)
				(type default)
			)
			(layer "B.SilkS")
		)
		(fp_line
			(start 0.7874 0.4064)
			(end 0.7874 -0.4064)
			(stroke
				(width 0.1524)
				(type default)
			)
			(layer "B.SilkS")
		)
		(fp_line
			(start -0.7874 -0.4064)
			(end -0.7874 0.4064)
			(stroke
				(width 0.1524)
				(type default)
			)
			(layer "B.SilkS")
		)
		(fp_line
			(start 0.7874 -0.4064)
			(end -0.7874 -0.4064)
			(stroke
				(width 0.1524)
				(type default)
			)
			(layer "B.SilkS")
		)
		(fp_line
			(start -0.67945 0.3048)
			(end -0.120396 0.3048)
			(stroke
				(width 0.1)
				(type default)
			)
			(layer "B.Fab")
		)
		(fp_line
			(start -0.120396 0.3048)
			(end -0.120396 0.2794)
			(stroke
				(width 0.1)
				(type default)
			)
			(layer "B.Fab")
		)
		(fp_line
			(start 0.12065 0.3048)
			(end 0.67945 0.3048)
			(stroke
				(width 0.1)
				(type default)
			)
			(layer "B.Fab")
		)
		(fp_line
			(start 0.67945 0.3048)
			(end 0.67945 -0.305054)
			(stroke
				(width 0.1)
				(type default)
			)
			(layer "B.Fab")
		)
		(fp_line
			(start -0.120396 0.2794)
			(end 0.12065 0.2794)
			(stroke
				(width 0.1)
				(type default)
			)
			(layer "B.Fab")
		)
		(fp_line
			(start 0.12065 0.2794)
			(end 0.12065 0.3048)
			(stroke
				(width 0.1)
				(type default)
			)
			(layer "B.Fab")
		)
		(fp_line
			(start -0.12065 -0.2794)
			(end -0.12065 -0.3048)
			(stroke
				(width 0.1)
				(type default)
			)
			(layer "B.Fab")
		)
		(fp_line
			(start 0.12065 -0.2794)
			(end -0.12065 -0.2794)
			(stroke
				(width 0.1)
				(type default)
			)
			(layer "B.Fab")
		)
		(fp_line
			(start -0.67945 -0.3048)
			(end -0.67945 0.3048)
			(stroke
				(width 0.1)
				(type default)
			)
			(layer "B.Fab")
		)
		(fp_line
			(start -0.12065 -0.3048)
			(end -0.67945 -0.3048)
			(stroke
				(width 0.1)
				(type default)
			)
			(layer "B.Fab")
		)
		(fp_line
			(start 0.12065 -0.305054)
			(end 0.12065 -0.2794)
			(stroke
				(width 0.1)
				(type default)
			)
			(layer "B.Fab")
		)
		(fp_line
			(start 0.67945 -0.305054)
			(end 0.12065 -0.305054)
			(stroke
				(width 0.1)
				(type default)
			)
			(layer "B.Fab")
		)
		(pad "1" smd circle
			(at 0.40005 0 90)
			(size 0 0)
			(layers "B.Cu" "B.Mask" "B.Paste")
			(net "P3V3_OCP_SFF")
		)
		(pad "2" smd circle
			(at -0.40005 0 90)
			(size 0 0)
			(layers "B.Cu" "B.Mask" "B.Paste")
			(net "OCP_SFF_ID0")
		)
	)
)
